FILE_TYPE = MULTI_PHYS_TABLE;
PART 'MOSFETN_1D3S'
{========================================================================================}
:PACK_TYPE | MATERIAL | PART_NUMBER    = ENVCOMP                            | PART_NUMBER  | JEDEC_TYPE         | CLASS | DESCRIPTION                                                       | HEIGHT     | COMPONENT_TYPE | LPID           | SPEED_URL                                                                                                                       | STATUS        | RPL   | AML | BUS_UNIT      | DAYS  ;
{========================================================================================}
'SOT5'    | 'IC'     | 'G68777-001'(!) = 'Y/E;Y/E;YES;UNK;ok;VLD'           | 'G68777-001' | 'SOT669A'          | 'IC'  | 'IC,DS,FET N,LFPAK,PH0925CL'                                      | '0.047 IN' | 'SMTOTHER'     | '2457'         | 'http://speed.intel.com:8081/speed/module/pdm/item/pdm_item_detail_direct.asp?item_cde=G68777-001&item_rev=01&url_param=unused' | 'Design'      | 'NO'  | '1' | 'SMO_IC'      | '???'
'SOT5'    | 'EMPTY'  | 'G68777-001'(!) = 'Y/E;Y/E;YES;UNK;ok;VLD'           | 'G68777-001' | 'SOT669A'          | 'IO'  | 'IC,DS,FET N,LFPAK,PH0925CL'                                      | '0.047 IN' | 'SMTOTHER'     | '2457'         | 'http://speed.intel.com:8081/speed/module/pdm/item/pdm_item_detail_direct.asp?item_cde=G68777-001&item_rev=01&url_param=unused' | 'Design'      | 'NO'  | '1' | 'SMO_IC'      | '???'
END_PART
END.
